# BASEBOARD_FAB2 (Tioga Pass) — schematic netlist excerpt (pin names and nets, part order shuffled) for the footprints in the layout excerpt that follows; sources: Cadence DE-HDL packaged netlist, KiCad conversion of Wiwynn_Tioga_Pass_MB.brd

J1A2  SCONN288_H44441004  SCONN  pkg PIP  page 85
  \12v\(1)  = P12V_NVDIMM_KLM
  VSS(93)  = GND
  DQ(4)  = M_L_DQ<5>
  VSS(92)  = GND
  DQ(0)  = M_L_DQ<1>
  VSS(91)  = GND
  DQS9P  = M_L_DQS_DP<9>
  DQS9N  = M_L_DQS_DN<9>
  VSS(90)  = GND
  DQ(6)  = M_L_DQ<7>
  VSS(89)  = GND
  DQ(2)  = M_L_DQ<3>
  VSS(88)  = GND
  DQ(12)  = M_L_DQ<13>
  VSS(87)  = GND
  DQ(8)  = M_L_DQ<9>
  VSS(86)  = GND
  DQS10P  = M_L_DQS_DP<10>
  DQS10N  = M_L_DQS_DN<10>
  VSS(85)  = GND
  DQ(14)  = M_L_DQ<15>
  VSS(84)  = GND
  DQ(10)  = M_L_DQ<11>
  VSS(83)  = GND
  DQ(20)  = M_L_DQ<21>
  VSS(82)  = GND
  DQ(16)  = M_L_DQ<17>
  VSS(81)  = GND
  DQS11P  = M_L_DQS_DP<11>
  DQS11N  = M_L_DQS_DN<11>
  VSS(80)  = GND
  DQ(22)  = M_L_DQ<23>
  VSS(79)  = GND
  DQ(18)  = M_L_DQ<19>
  VSS(78)  = GND
  DQ(28)  = M_L_DQ<29>
  VSS(77)  = GND
  DQ(24)  = M_L_DQ<25>
  VSS(76)  = GND
  DQS12P  = M_L_DQS_DP<12>
  DQS12N  = M_L_DQS_DN<12>
  VSS(75)  = GND
  DQ(30)  = M_L_DQ<31>
  VSS(74)  = GND
  DQ(26)  = M_L_DQ<27>
  VSS(73)  = GND
  CB(4)  = M_L_ECC<5>
  VSS(72)  = GND
  CB(0)  = M_L_ECC<1>
  VSS(71)  = GND
  DQS17P  = M_L_DQS_DP<17>
  DQS17N  = M_L_DQS_DN<17>
  VSS(70)  = GND
  CB(6)  = M_L_ECC<7>
  VSS(69)  = GND
  CB(2)  = M_L_ECC<3>
  VSS(68)  = GND
  RESET_N  = M_KLM_RST_N
  VDD(25)  = PVDDQ_KLM
  CKE(0)  = M_L_CKE<0>
  VDD(24)  = PVDDQ_KLM
  ACT_N  = M_L_ACT_N
  BG(0)  = M_L_BG<0>
  VDD(23)  = PVDDQ_KLM
  A12  = M_L_MA<12>
  A9  = M_L_MA<9>
  VDD(22)  = PVDDQ_KLM
  A8  = M_L_MA<8>
  A6  = M_L_MA<6>
  VDD(21)  = PVDDQ_KLM
  A3  = M_L_MA<3>
  A1  = M_L_MA<1>
  VDD(20)  = PVDDQ_KLM
  CK0P  = M_L_CLK_DP<0>
  CK0N  = M_L_CLK_DN<0>
  VDD(19)  = PVDDQ_KLM
  VTT(1)  = PVTT_KLM
  EVENT_N  = FM_DIMM_EVENT_COD_N
  A0  = M_L_MA<0>
  VDD(18)  = PVDDQ_KLM
  BA(0)  = M_L_BA<0>
  A16_RAS_N  = M_L_MA<16>
  VDD(17)  = PVDDQ_KLM
  S0_N  = M_L_CS_N<0>
  VDD(16)  = PVDDQ_KLM
  A15_CAS_N  = M_L_MA<15>
  ODT(0)  = M_L_ODT<0>
  VDD(15)  = PVDDQ_KLM
  S1_N  = M_L_CS_N<1>
  VDD(14)  = PVDDQ_KLM
  ODT(1)  = M_L_ODT<1>
  VDD(13)  = PVDDQ_KLM
  S2_N_C(0)  = M_L_CS_N<2>
  VSS(67)  = GND
  DQ(36)  = M_L_DQ<37>
  VSS(66)  = GND
  DQ(32)  = M_L_DQ<33>
  VSS(65)  = GND
  DQS13P  = M_L_DQS_DP<13>
  DQS13N  = M_L_DQS_DN<13>
  VSS(64)  = GND
  DQ(38)  = M_L_DQ<39>
  VSS(63)  = GND
  DQ(34)  = M_L_DQ<35>
  VSS(62)  = GND
  DQ(44)  = M_L_DQ<45>
  VSS(61)  = GND
  DQ(40)  = M_L_DQ<41>
  VSS(60)  = GND
  DQS14P  = M_L_DQS_DP<14>
  DQS14N  = M_L_DQS_DN<14>
  VSS(59)  = GND
  DQ(46)  = M_L_DQ<47>
  VSS(58)  = GND
  DQ(42)  = M_L_DQ<43>
  VSS(57)  = GND
  DQ(52)  = M_L_DQ<53>
  VSS(56)  = GND
  DQ(48)  = M_L_DQ<49>
  VSS(55)  = GND
  DQS15P  = M_L_DQS_DP<15>
  DQS15N  = M_L_DQS_DN<15>
  VSS(54)  = GND
  DQ(54)  = M_L_DQ<55>
  VSS(53)  = GND
  DQ(50)  = M_L_DQ<51>
  VSS(52)  = GND
  DQ(60)  = M_L_DQ<61>
  VSS(51)  = GND
  DQ(56)  = M_L_DQ<57>
  VSS(50)  = GND
  DQS16P  = M_L_DQS_DP<16>
  DQS16N  = M_L_DQS_DN<16>
  VSS(49)  = GND
  DQ(62)  = M_L_DQ<63>
  VSS(48)  = GND
  DQ(58)  = M_L_DQ<59>
  VSS(47)  = GND
  SA(0)  = GND
  SA(1)  = PVPP_KLM
  SCL  = SMB_DDR_KLM_VPP_SCL
  VPP(4)  = PVPP_KLM
  VPP(3)  = PVPP_KLM
  RFU(2)  = TP_CH_L_DIMM_L0_RFU_2
  \12v\(0)  = P12V_NVDIMM_KLM
  VREFCA  = M_L_VREF
  VSS(46)  = GND
  DQ(5)  = M_L_DQ<4>
  VSS(45)  = GND
  DQ(1)  = M_L_DQ<0>
  VSS(44)  = GND
  DQS0N  = M_L_DQS_DN<0>
  DQS0P  = M_L_DQS_DP<0>
  VSS(43)  = GND
  DQ(7)  = M_L_DQ<6>
  VSS(42)  = GND
  DQ(3)  = M_L_DQ<2>
  VSS(41)  = GND
  DQ(13)  = M_L_DQ<12>
  VSS(40)  = GND
  DQ(9)  = M_L_DQ<8>
  VSS(39)  = GND
  DQS1N  = M_L_DQS_DN<1>
  DQS1P  = M_L_DQS_DP<1>
  VSS(38)  = GND
  DQ(15)  = M_L_DQ<14>
  VSS(37)  = GND
  DQ(11)  = M_L_DQ<10>
  VSS(36)  = GND
  DQ(21)  = M_L_DQ<20>
  VSS(35)  = GND
  DQ(17)  = M_L_DQ<16>
  VSS(34)  = GND
  DQS2N  = M_L_DQS_DN<2>
  DQS2P  = M_L_DQS_DP<2>
  VSS(33)  = GND
  DQ(23)  = M_L_DQ<22>
  VSS(32)  = GND
  DQ(19)  = M_L_DQ<18>
  VSS(31)  = GND
  DQ(29)  = M_L_DQ<28>
  VSS(30)  = GND
  DQ(25)  = M_L_DQ<24>
  VSS(29)  = GND
  DQS3N  = M_L_DQS_DN<3>
  DQS3P  = M_L_DQS_DP<3>
  VSS(28)  = GND
  DQ(31)  = M_L_DQ<30>
  VSS(27)  = GND
  DQ(27)  = M_L_DQ<26>
  VSS(26)  = GND
  CB(5)  = M_L_ECC<4>
  VSS(25)  = GND
  CB(1)  = M_L_ECC<0>
  VSS(24)  = GND
  DQS8N  = M_L_DQS_DN<8>
  DQS8P  = M_L_DQS_DP<8>
  VSS(23)  = GND
  CB(7)  = M_L_ECC<6>
  VSS(22)  = GND
  CB(3)  = M_L_ECC<2>
  VSS(21)  = GND
  CKE(1)  = M_L_CKE<1>
  VDD(12)  = PVDDQ_KLM
  RFU(0)  = TP_CH_L_DIMM_L0_RFU_0
  VDD(11)  = PVDDQ_KLM
  BG(1)  = M_L_BG<1>
  ALERT_N  = M_L_ALERT_N
  VDD(10)  = PVDDQ_KLM
  A11  = M_L_MA<11>
  A7  = M_L_MA<7>
  VDD(9)  = PVDDQ_KLM
  A5  = M_L_MA<5>
  A4  = M_L_MA<4>
  VDD(8)  = PVDDQ_KLM
  A2  = M_L_MA<2>
  VDD(7)  = PVDDQ_KLM
  CK1P  = M_L_CLK_DP<1>
  CK1N  = M_L_CLK_DN<1>
  VDD(6)  = PVDDQ_KLM
  VTT(0)  = PVTT_KLM
  PAR  = M_L_PAR
  VDD(5)  = PVDDQ_KLM
  BA(1)  = M_L_BA<1>
  A10  = M_L_MA<10>
  VDD(4)  = PVDDQ_KLM
  RFU(1)  = TP_CH_L_DIMM_L0_RFU_1
  A14_WE_N  = M_L_MA<14>
  VDD(3)  = PVDDQ_KLM
  SAVE_N_NC  = FM_ADR_COMPLETE_KLM_N
  VDD(2)  = PVDDQ_KLM
  A13  = M_L_MA<13>
  VDD(1)  = PVDDQ_KLM
  A17  = M_L_MA<17>
  C(2)  = M_L_C<2>
  VDD(0)  = PVDDQ_KLM
  S3_N_C(1)  = M_L_CS_N<3>
  SA(2)  = GND
  VSS(20)  = GND
  DQ(37)  = M_L_DQ<36>
  VSS(19)  = GND
  DQ(33)  = M_L_DQ<32>
  VSS(18)  = GND
  DQS4N  = M_L_DQS_DN<4>
  DQS4P  = M_L_DQS_DP<4>
  VSS(17)  = GND
  DQ(39)  = M_L_DQ<38>
  VSS(16)  = GND
  DQ(35)  = M_L_DQ<34>
  VSS(15)  = GND
  DQ(45)  = M_L_DQ<44>
  VSS(14)  = GND
  DQ(41)  = M_L_DQ<40>
  VSS(13)  = GND
  DQS5N  = M_L_DQS_DN<5>
  DQS5P  = M_L_DQS_DP<5>
  VSS(12)  = GND
  DQ(47)  = M_L_DQ<46>
  VSS(11)  = GND
  DQ(43)  = M_L_DQ<42>
  VSS(10)  = GND
  DQ(53)  = M_L_DQ<52>
  VSS(9)  = GND
  DQ(49)  = M_L_DQ<48>
  VSS(8)  = GND
  DQS6N  = M_L_DQS_DN<6>
  DQS6P  = M_L_DQS_DP<6>
  VSS(7)  = GND
  DQ(55)  = M_L_DQ<54>
  VSS(6)  = GND
  DQ(51)  = M_L_DQ<50>
  VSS(5)  = GND
  DQ(61)  = M_L_DQ<60>
  VSS(4)  = GND
  DQ(57)  = M_L_DQ<56>
  VSS(3)  = GND
  DQS7N  = M_L_DQS_DN<7>
  DQS7P  = M_L_DQS_DP<7>
  VSS(2)  = GND
  DQ(63)  = M_L_DQ<62>
  VSS(1)  = GND
  DQ(59)  = M_L_DQ<58>
  VSS(0)  = GND
  VDDSPD  = PVPP_KLM
  SDA  = SMB_DDR_KLM_VPP_SDA
  VPP(1)  = PVPP_KLM
  VPP(0)  = PVPP_KLM
  VPP(2)  = PVPP_KLM

(kicad_pcb
	(version 20260206)
	(generator "pcbnew")
	(generator_version "10.0")
	(general
		(thickness 1.6)
		(legacy_teardrops no)
	)
	(paper "A4")
	(title_block
		(title "Wiwynn_Tioga_Pass_MB.brd")
		(comment 1 "Tioga Pass / footprint 2031 of 4770 (J1A2), pads 1-51 of 291")
	)
	(layers
		(0 "F.Cu" signal "TOP")
		(4 "In1.Cu" signal "L2GND")
		(6 "In2.Cu" signal "L3")
		(8 "In3.Cu" signal "L4GND")
		(10 "In4.Cu" signal "L5")
		(12 "In5.Cu" signal "L6GND")
		(14 "In6.Cu" signal "L7VCC")
		(16 "In7.Cu" signal "L8VCC")
		(18 "In8.Cu" signal "L9GND")
		(20 "In9.Cu" signal "L10")
		(22 "In10.Cu" signal "L11GND")
		(24 "In11.Cu" signal "L12")
		(26 "In12.Cu" signal "L13GND")
		(2 "B.Cu" signal "BOTTOM")
		(9 "F.Adhes" user "F.Adhesive")
		(11 "B.Adhes" user "B.Adhesive")
		(13 "F.Paste" user "Package Geometry/Pastemask Top")
		(15 "B.Paste" user "Package Geometry/Pastemask Bottom")
		(5 "F.SilkS" user "Ref Des/Silkscreen Top")
		(7 "B.SilkS" user "Ref Des/Silkscreen Bottom")
		(1 "F.Mask" user "Board Geometry/Soldermask Top")
		(3 "B.Mask" user "Board Geometry/Soldermask Bottom")
		(17 "Dwgs.User" user "User.Drawings")
		(19 "Cmts.User" user "User.Comments")
		(21 "Eco1.User" user "User.Eco1")
		(23 "Eco2.User" user "User.Eco2")
		(25 "Edge.Cuts" user "Board Geometry/Outline")
		(27 "Margin" user)
		(31 "F.CrtYd" user "Package Geometry/Place Bound Top")
		(29 "B.CrtYd" user "Package Geometry/Place Bound Bottom")
		(35 "F.Fab" user "Ref Des/Assembly Top")
		(33 "B.Fab" user "Ref Des/Assembly Bottom")
	)
	(footprint ""
		(layer "F.Cu")
		(at 29.699458 -142.6718 90)
		(property "Reference" "J1A2"
			(at -2.623312 42.436542 0)
			(unlocked yes)
			(layer "F.SilkS")
			(effects
				(font
					(size 0.7874 0.5842)
					(thickness 0.1524)
				)
				(justify left)
			)
		)
		(property "Value" ""
			(at 0 0 90)
			(layer "F.Fab")
			(effects
				(font
					(size 1.27 1.27)
				)
			)
		)
		(duplicate_pad_numbers_are_jumpers no)
		(pad "" thru_hole circle
			(at 2.29997 -5.649976 90)
			(size 2.8194 2.8194)
			(drill 2.4384)
			(layers "*.Cu" "*.Mask")
			(remove_unused_layers no)
			(clearance 0.127)
			(thermal_gap 0.127)
		)
		(pad "" thru_hole oval
			(at 2.29997 68.90004 90)
			(size 2.8194 1.5748)
			(drill oval 2.4384 1.1938)
			(layers "*.Cu" "*.Mask")
			(remove_unused_layers no)
			(clearance 0.127)
			(thermal_gap 0.127)
		)
		(pad "" thru_hole circle
			(at 2.29997 132.299964 90)
			(size 2.8194 2.8194)
			(drill 2.4384)
			(layers "*.Cu" "*.Mask")
			(remove_unused_layers no)
			(clearance 0.127)
			(thermal_gap 0.127)
		)
		(pad "1" smd rect
			(at 0 0 90)
			(size 1.8034 0.508)
			(layers "F.Cu" "F.Mask" "F.Paste")
			(net "P12V_NVDIMM_KLM")
		)
		(pad "2" smd rect
			(at 0 0.849884 90)
			(size 1.8034 0.508)
			(layers "F.Cu" "F.Mask" "F.Paste")
			(net "GND")
		)
		(pad "3" smd rect
			(at 0 1.700022 90)
			(size 1.8034 0.508)
			(layers "F.Cu" "F.Mask" "F.Paste")
			(net "M_L_DQ<5>")
		)
		(pad "4" smd rect
			(at 0 2.549906 90)
			(size 1.8034 0.508)
			(layers "F.Cu" "F.Mask" "F.Paste")
			(net "GND")
		)
		(pad "5" smd rect
			(at 0 3.400044 90)
			(size 1.8034 0.508)
			(layers "F.Cu" "F.Mask" "F.Paste")
			(net "M_L_DQ<1>")
		)
		(pad "6" smd rect
			(at 0 4.249928 90)
			(size 1.8034 0.508)
			(layers "F.Cu" "F.Mask" "F.Paste")
			(net "GND")
		)
		(pad "7" smd rect
			(at 0 5.100066 90)
			(size 1.8034 0.508)
			(layers "F.Cu" "F.Mask" "F.Paste")
			(net "M_L_DQS_DP<9>")
		)
		(pad "8" smd rect
			(at 0 5.94995 90)
			(size 1.8034 0.508)
			(layers "F.Cu" "F.Mask" "F.Paste")
			(net "M_L_DQS_DN<9>")
		)
		(pad "9" smd rect
			(at 0 6.800088 90)
			(size 1.8034 0.508)
			(layers "F.Cu" "F.Mask" "F.Paste")
			(net "GND")
		)
		(pad "10" smd rect
			(at 0 7.649972 90)
			(size 1.8034 0.508)
			(layers "F.Cu" "F.Mask" "F.Paste")
			(net "M_L_DQ<7>")
		)
		(pad "11" smd rect
			(at 0 8.50011 90)
			(size 1.8034 0.508)
			(layers "F.Cu" "F.Mask" "F.Paste")
			(net "GND")
		)
		(pad "12" smd rect
			(at 0 9.349994 90)
			(size 1.8034 0.508)
			(layers "F.Cu" "F.Mask" "F.Paste")
			(net "M_L_DQ<3>")
		)
		(pad "13" smd rect
			(at 0 10.199878 90)
			(size 1.8034 0.508)
			(layers "F.Cu" "F.Mask" "F.Paste")
			(net "GND")
		)
		(pad "14" smd rect
			(at 0 11.050016 90)
			(size 1.8034 0.508)
			(layers "F.Cu" "F.Mask" "F.Paste")
			(net "M_L_DQ<13>")
		)
		(pad "15" smd rect
			(at 0 11.8999 90)
			(size 1.8034 0.508)
			(layers "F.Cu" "F.Mask" "F.Paste")
			(net "GND")
		)
		(pad "16" smd rect
			(at 0 12.750038 90)
			(size 1.8034 0.508)
			(layers "F.Cu" "F.Mask" "F.Paste")
			(net "M_L_DQ<9>")
		)
		(pad "17" smd rect
			(at 0 13.599922 90)
			(size 1.8034 0.508)
			(layers "F.Cu" "F.Mask" "F.Paste")
			(net "GND")
		)
		(pad "18" smd rect
			(at 0 14.45006 90)
			(size 1.8034 0.508)
			(layers "F.Cu" "F.Mask" "F.Paste")
			(net "M_L_DQS_DP<10>")
		)
		(pad "19" smd rect
			(at 0 15.299944 90)
			(size 1.8034 0.508)
			(layers "F.Cu" "F.Mask" "F.Paste")
			(net "M_L_DQS_DN<10>")
		)
		(pad "20" smd rect
			(at 0 16.150082 90)
			(size 1.8034 0.508)
			(layers "F.Cu" "F.Mask" "F.Paste")
			(net "GND")
		)
		(pad "21" smd rect
			(at 0 16.999966 90)
			(size 1.8034 0.508)
			(layers "F.Cu" "F.Mask" "F.Paste")
			(net "M_L_DQ<15>")
		)
		(pad "22" smd rect
			(at 0 17.850104 90)
			(size 1.8034 0.508)
			(layers "F.Cu" "F.Mask" "F.Paste")
			(net "GND")
		)
		(pad "23" smd rect
			(at 0 18.699988 90)
			(size 1.8034 0.508)
			(layers "F.Cu" "F.Mask" "F.Paste")
			(net "M_L_DQ<11>")
		)
		(pad "24" smd rect
			(at 0 19.550126 90)
			(size 1.8034 0.508)
			(layers "F.Cu" "F.Mask" "F.Paste")
			(net "GND")
		)
		(pad "25" smd rect
			(at 0 20.40001 90)
			(size 1.8034 0.508)
			(layers "F.Cu" "F.Mask" "F.Paste")
			(net "M_L_DQ<21>")
		)
		(pad "26" smd rect
			(at 0 21.249894 90)
			(size 1.8034 0.508)
			(layers "F.Cu" "F.Mask" "F.Paste")
			(net "GND")
		)
		(pad "27" smd rect
			(at 0 22.100032 90)
			(size 1.8034 0.508)
			(layers "F.Cu" "F.Mask" "F.Paste")
			(net "M_L_DQ<17>")
		)
		(pad "28" smd rect
			(at 0 22.949916 90)
			(size 1.8034 0.508)
			(layers "F.Cu" "F.Mask" "F.Paste")
			(net "GND")
		)
		(pad "29" smd rect
			(at 0 23.800054 90)
			(size 1.8034 0.508)
			(layers "F.Cu" "F.Mask" "F.Paste")
			(net "M_L_DQS_DP<11>")
		)
		(pad "30" smd rect
			(at 0 24.649938 90)
			(size 1.8034 0.508)
			(layers "F.Cu" "F.Mask" "F.Paste")
			(net "M_L_DQS_DN<11>")
		)
		(pad "31" smd rect
			(at 0 25.500076 90)
			(size 1.8034 0.508)
			(layers "F.Cu" "F.Mask" "F.Paste")
			(net "GND")
		)
		(pad "32" smd rect
			(at 0 26.34996 90)
			(size 1.8034 0.508)
			(layers "F.Cu" "F.Mask" "F.Paste")
			(net "M_L_DQ<23>")
		)
		(pad "33" smd rect
			(at 0 27.200098 90)
			(size 1.8034 0.508)
			(layers "F.Cu" "F.Mask" "F.Paste")
			(net "GND")
		)
		(pad "34" smd rect
			(at 0 28.049982 90)
			(size 1.8034 0.508)
			(layers "F.Cu" "F.Mask" "F.Paste")
			(net "M_L_DQ<19>")
		)
		(pad "35" smd rect
			(at 0 28.90012 90)
			(size 1.8034 0.508)
			(layers "F.Cu" "F.Mask" "F.Paste")
			(net "GND")
		)
		(pad "36" smd rect
			(at 0 29.750004 90)
			(size 1.8034 0.508)
			(layers "F.Cu" "F.Mask" "F.Paste")
			(net "M_L_DQ<29>")
		)
		(pad "37" smd rect
			(at 0 30.599888 90)
			(size 1.8034 0.508)
			(layers "F.Cu" "F.Mask" "F.Paste")
			(net "GND")
		)
		(pad "38" smd rect
			(at 0 31.450026 90)
			(size 1.8034 0.508)
			(layers "F.Cu" "F.Mask" "F.Paste")
			(net "M_L_DQ<25>")
		)
		(pad "39" smd rect
			(at 0 32.29991 90)
			(size 1.8034 0.508)
			(layers "F.Cu" "F.Mask" "F.Paste")
			(net "GND")
		)
		(pad "40" smd rect
			(at 0 33.150048 90)
			(size 1.8034 0.508)
			(layers "F.Cu" "F.Mask" "F.Paste")
			(net "M_L_DQS_DP<12>")
		)
		(pad "41" smd rect
			(at 0 33.999932 90)
			(size 1.8034 0.508)
			(layers "F.Cu" "F.Mask" "F.Paste")
			(net "M_L_DQS_DN<12>")
		)
		(pad "42" smd rect
			(at 0 34.85007 90)
			(size 1.8034 0.508)
			(layers "F.Cu" "F.Mask" "F.Paste")
			(net "GND")
		)
		(pad "43" smd rect
			(at 0 35.699954 90)
			(size 1.8034 0.508)
			(layers "F.Cu" "F.Mask" "F.Paste")
			(net "M_L_DQ<31>")
		)
		(pad "44" smd rect
			(at 0 36.550092 90)
			(size 1.8034 0.508)
			(layers "F.Cu" "F.Mask" "F.Paste")
			(net "GND")
		)
		(pad "45" smd rect
			(at 0 37.399976 90)
			(size 1.8034 0.508)
			(layers "F.Cu" "F.Mask" "F.Paste")
			(net "M_L_DQ<27>")
		)
		(pad "46" smd rect
			(at 0 38.250114 90)
			(size 1.8034 0.508)
			(layers "F.Cu" "F.Mask" "F.Paste")
			(net "GND")
		)
		(pad "47" smd rect
			(at 0 39.099998 90)
			(size 1.8034 0.508)
			(layers "F.Cu" "F.Mask" "F.Paste")
			(net "M_L_ECC<5>")
		)
		(pad "48" smd rect
			(at 0 39.949882 90)
			(size 1.8034 0.508)
			(layers "F.Cu" "F.Mask" "F.Paste")
			(net "GND")
		)
	)
)
